# BASEBOARD_FAB2 (Tioga Pass) — schematic netlist excerpt (pin names and nets, part order shuffled) for the footprints in the layout excerpt that follows; sources: Cadence DE-HDL packaged netlist, KiCad conversion of Wiwynn_Tioga_Pass_MB.brd

R6P22  RES  4.75K 1% EMPTY  pkg 0402  page 102 : A = FM_HBW_BYPASS_LOWBW_N ; B = GND
C25W29  CAP  10UF 4V 20% X6S  pkg 0603LF  page 149 : A = P1V15_AUX_BMC ; B = GND
C6N7  CAP_A  22.0UF 4V 20% X6S  pkg 0603V  page 205 : A = PVSA_CPU0 ; B = GND

(kicad_pcb
	(version 20260206)
	(generator "pcbnew")
	(generator_version "10.0")
	(general
		(thickness 1.6)
		(legacy_teardrops no)
	)
	(paper "A4")
	(title_block
		(title "Wiwynn_Tioga_Pass_MB.brd")
		(comment 1 "Tioga Pass / footprints 3929-3931 of 4770")
	)
	(layers
		(0 "F.Cu" signal "TOP")
		(4 "In1.Cu" signal "L2GND")
		(6 "In2.Cu" signal "L3")
		(8 "In3.Cu" signal "L4GND")
		(10 "In4.Cu" signal "L5")
		(12 "In5.Cu" signal "L6GND")
		(14 "In6.Cu" signal "L7VCC")
		(16 "In7.Cu" signal "L8VCC")
		(18 "In8.Cu" signal "L9GND")
		(20 "In9.Cu" signal "L10")
		(22 "In10.Cu" signal "L11GND")
		(24 "In11.Cu" signal "L12")
		(26 "In12.Cu" signal "L13GND")
		(2 "B.Cu" signal "BOTTOM")
		(9 "F.Adhes" user "F.Adhesive")
		(11 "B.Adhes" user "B.Adhesive")
		(13 "F.Paste" user "Package Geometry/Pastemask Top")
		(15 "B.Paste" user "Package Geometry/Pastemask Bottom")
		(5 "F.SilkS" user "Ref Des/Silkscreen Top")
		(7 "B.SilkS" user "Ref Des/Silkscreen Bottom")
		(1 "F.Mask" user "Board Geometry/Soldermask Top")
		(3 "B.Mask" user "Board Geometry/Soldermask Bottom")
		(17 "Dwgs.User" user "User.Drawings")
		(19 "Cmts.User" user "User.Comments")
		(21 "Eco1.User" user "User.Eco1")
		(23 "Eco2.User" user "User.Eco2")
		(25 "Edge.Cuts" user "Board Geometry/Outline")
		(27 "Margin" user)
		(31 "F.CrtYd" user "Package Geometry/Place Bound Top")
		(29 "B.CrtYd" user "Package Geometry/Place Bound Bottom")
		(35 "F.Fab" user "Ref Des/Assembly Top")
		(33 "B.Fab" user "Ref Des/Assembly Bottom")
	)
	(footprint ""
		(layer "B.Cu")
		(at 417.746434 -34.186368 -90)
		(property "Reference" "C25W29"
			(at -0.97536 0.76708 0)
			(unlocked yes)
			(layer "B.SilkS")
			(effects
				(font
					(size 0.4064 0.254)
					(thickness 0.1524)
				)
				(justify mirror)
			)
		)
		(property "Value" ""
			(at 0 0 90)
			(layer "B.Fab")
			(effects
				(font
					(size 1.27 1.27)
				)
				(justify mirror)
			)
		)
		(duplicate_pad_numbers_are_jumpers no)
		(fp_poly
			(pts
				(xy 0.4953 -0.2032) (xy -0.4953 -0.2032) (xy -0.4953 1.6002) (xy 0.4953 1.6002)
			)
			(stroke
				(width 0)
				(type default)
			)
			(fill no)
			(layer "B.CrtYd")
		)
		(fp_line
			(start -0.4953 1.6002)
			(end 0.4953 1.6002)
			(stroke
				(width 0.1)
				(type default)
			)
			(layer "B.Fab")
		)
		(fp_line
			(start 0.4953 1.6002)
			(end 0.4953 -0.2032)
			(stroke
				(width 0.1)
				(type default)
			)
			(layer "B.Fab")
		)
		(fp_line
			(start -0.4953 -0.2032)
			(end -0.4953 1.6002)
			(stroke
				(width 0.1)
				(type default)
			)
			(layer "B.Fab")
		)
		(fp_line
			(start 0.4953 -0.2032)
			(end -0.4953 -0.2032)
			(stroke
				(width 0.1)
				(type default)
			)
			(layer "B.Fab")
		)
		(pad "1" smd rect
			(at 0 0 90)
			(size 0.762 0.889)
			(layers "B.Cu" "B.Mask" "B.Paste")
			(net "P1V15_AUX_BMC")
		)
		(pad "2" smd rect
			(at 0 1.397 90)
			(size 0.762 0.889)
			(layers "B.Cu" "B.Mask" "B.Paste")
			(net "GND")
		)
		(zone
			(layer "B.Cu")
			(hatch none 0.5)
			(connect_pads
				(clearance 0)
			)
			(min_thickness 0.25)
			(keepout
				(tracks not_allowed)
				(vias allowed)
				(pads allowed)
				(copperpour not_allowed)
				(footprints allowed)
			)
			(placement
				(enabled no)
				(sheetname "")
			)
			(fill
				(thermal_gap 0.5)
				(thermal_bridge_width 0.5)
				(island_removal_mode 0)
			)
			(polygon
				(pts
					(xy 417.301934 -33.805368) (xy 417.301934 -34.567368) (xy 416.793934 -34.567368) (xy 416.793934 -33.805368)
				)
			)
		)
	)
	(footprint ""
		(layer "B.Cu")
		(at 167.288718 -74.135234)
		(property "Reference" "R6P22"
			(at 0 0 0)
			(layer "B.SilkS")
			(hide yes)
			(effects
				(font
					(size 1.27 1.27)
				)
				(justify mirror)
			)
		)
		(property "Value" ""
			(at 0 0 0)
			(layer "B.Fab")
			(effects
				(font
					(size 1.27 1.27)
				)
				(justify mirror)
			)
		)
		(duplicate_pad_numbers_are_jumpers no)
		(fp_poly
			(pts
				(xy 0.2794 -0.1016) (xy -0.2794 -0.1016) (xy -0.2794 0.9906) (xy 0.2794 0.9906)
			)
			(stroke
				(width 0)
				(type default)
			)
			(fill no)
			(layer "B.CrtYd")
		)
		(fp_line
			(start -0.2794 -0.1016)
			(end 0.2794 -0.1016)
			(stroke
				(width 0.1)
				(type default)
			)
			(layer "B.Fab")
		)
		(fp_line
			(start -0.2794 0.9906)
			(end -0.2794 -0.1016)
			(stroke
				(width 0.1)
				(type default)
			)
			(layer "B.Fab")
		)
		(fp_line
			(start 0.2794 -0.1016)
			(end 0.2794 0.9906)
			(stroke
				(width 0.1)
				(type default)
			)
			(layer "B.Fab")
		)
		(fp_line
			(start 0.2794 0.9906)
			(end -0.2794 0.9906)
			(stroke
				(width 0.1)
				(type default)
			)
			(layer "B.Fab")
		)
		(pad "1" smd rect
			(at 0 0 180)
			(size 0.508 0.508)
			(layers "B.Cu" "B.Mask" "B.Paste")
			(net "FM_HBW_BYPASS_LOWBW_N")
		)
		(pad "2" smd rect
			(at 0 0.889 180)
			(size 0.508 0.508)
			(layers "B.Cu" "B.Mask" "B.Paste")
			(net "GND")
		)
		(zone
			(layer "B.Cu")
			(hatch none 0.5)
			(connect_pads
				(clearance 0)
			)
			(min_thickness 0.25)
			(keepout
				(tracks allowed)
				(vias not_allowed)
				(pads allowed)
				(copperpour not_allowed)
				(footprints allowed)
			)
			(placement
				(enabled no)
				(sheetname "")
			)
			(fill
				(thermal_gap 0.5)
				(thermal_bridge_width 0.5)
				(island_removal_mode 0)
			)
			(polygon
				(pts
					(xy 167.542718 -73.881234) (xy 167.034718 -73.881234) (xy 167.034718 -73.500234) (xy 167.542718 -73.500234)
				)
			)
		)
		(zone
			(layer "B.Cu")
			(hatch none 0.5)
			(connect_pads
				(clearance 0)
			)
			(min_thickness 0.25)
			(keepout
				(tracks not_allowed)
				(vias allowed)
				(pads allowed)
				(copperpour not_allowed)
				(footprints allowed)
			)
			(placement
				(enabled no)
				(sheetname "")
			)
			(fill
				(thermal_gap 0.5)
				(thermal_bridge_width 0.5)
				(island_removal_mode 0)
			)
			(polygon
				(pts
					(xy 167.542718 -73.500234) (xy 167.034718 -73.500234) (xy 167.034718 -73.881234) (xy 167.542718 -73.881234)
				)
			)
		)
	)
	(footprint ""
		(layer "B.Cu")
		(at 214.503 -94.4372)
		(property "Reference" "C6N7"
			(at 0 0 0)
			(layer "B.SilkS")
			(hide yes)
			(effects
				(font
					(size 1.27 1.27)
				)
				(justify mirror)
			)
		)
		(property "Value" ""
			(at 0 0 0)
			(layer "B.Fab")
			(effects
				(font
					(size 1.27 1.27)
				)
				(justify mirror)
			)
		)
		(duplicate_pad_numbers_are_jumpers no)
		(fp_poly
			(pts
				(xy 0.4953 -0.2032) (xy -0.4953 -0.2032) (xy -0.4953 1.6002) (xy 0.4953 1.6002)
			)
			(stroke
				(width 0)
				(type default)
			)
			(fill no)
			(layer "B.CrtYd")
		)
		(fp_line
			(start -0.4953 -0.2032)
			(end -0.4953 1.6002)
			(stroke
				(width 0.1)
				(type default)
			)
			(layer "B.Fab")
		)
		(fp_line
			(start -0.4953 1.6002)
			(end 0.4953 1.6002)
			(stroke
				(width 0.1)
				(type default)
			)
			(layer "B.Fab")
		)
		(fp_line
			(start 0.4953 -0.2032)
			(end -0.4953 -0.2032)
			(stroke
				(width 0.1)
				(type default)
			)
			(layer "B.Fab")
		)
		(fp_line
			(start 0.4953 1.6002)
			(end 0.4953 -0.2032)
			(stroke
				(width 0.1)
				(type default)
			)
			(layer "B.Fab")
		)
		(pad "1" smd rect
			(at 0 0 180)
			(size 0.762 0.889)
			(layers "B.Cu" "B.Mask" "B.Paste")
			(net "PVSA_CPU0")
		)
		(pad "2" smd rect
			(at 0 1.397 180)
			(size 0.762 0.889)
			(layers "B.Cu" "B.Mask" "B.Paste")
			(net "GND")
		)
		(zone
			(layer "B.Cu")
			(hatch none 0.5)
			(connect_pads
				(clearance 0)
			)
			(min_thickness 0.25)
			(keepout
				(tracks not_allowed)
				(vias allowed)
				(pads allowed)
				(copperpour not_allowed)
				(footprints allowed)
			)
			(placement
				(enabled no)
				(sheetname "")
			)
			(fill
				(thermal_gap 0.5)
				(thermal_bridge_width 0.5)
				(island_removal_mode 0)
			)
			(polygon
				(pts
					(xy 214.884 -93.9927) (xy 214.122 -93.9927) (xy 214.122 -93.4847) (xy 214.884 -93.4847)
				)
			)
		)
	)
)
